# TIMECARD (Time Appliance Project (Time Card)) — schematic netlist excerpt (pin names and nets, part order shuffled) for the footprints in the layout excerpt that follows; sources: Cadence DE-HDL packaged netlist, KiCad conversion of R4006-B0001-02_R01.brd

C81  CAPACITOR  0.1UF 10V 10%  pkg SMC_0402R_H022  page 22 : \1\ = XP3R3V_FPGA ; \2\ = SG
C288  CAPACITOR  0.1UF 25V 10%  pkg SMC_0402R_H022  page 9 : \1\ = XP3R3V_AUX_PCIE ; \2\ = SG

(kicad_pcb
	(version 20260206)
	(generator "pcbnew")
	(generator_version "10.0")
	(general
		(thickness 1.6)
		(legacy_teardrops no)
	)
	(paper "A4")
	(title_block
		(title "timecard-production-celestica-r4006 — R4006-B0001-02_R01.brd")
		(comment 1 "Time Appliance Project (Time Card) / footprints 536-537 of 1113")
	)
	(layers
		(0 "F.Cu" signal "TOP")
		(4 "In1.Cu" signal "L02_GND1")
		(6 "In2.Cu" signal "L03_SIG1")
		(8 "In3.Cu" signal "L04_GND2")
		(10 "In4.Cu" signal "L05_VCC1")
		(12 "In5.Cu" signal "L06_VCC2")
		(14 "In6.Cu" signal "L07_GND3")
		(16 "In7.Cu" signal "L08_SIG2")
		(18 "In8.Cu" signal "L09_GND4")
		(2 "B.Cu" signal "BOTTOM")
		(9 "F.Adhes" user "F.Adhesive")
		(11 "B.Adhes" user "B.Adhesive")
		(13 "F.Paste" user "Package Geometry/Pastemask Top")
		(15 "B.Paste" user "Package Geometry/Pastemask Bottom")
		(5 "F.SilkS" user "Ref Des/Silkscreen Top")
		(7 "B.SilkS" user "Ref Des/Silkscreen Bottom")
		(1 "F.Mask" user "Board Geometry/Soldermask Top")
		(3 "B.Mask" user "Board Geometry/Soldermask Bottom")
		(17 "Dwgs.User" user "User.Drawings")
		(19 "Cmts.User" user "User.Comments")
		(21 "Eco1.User" user "User.Eco1")
		(23 "Eco2.User" user "User.Eco2")
		(25 "Edge.Cuts" user "Board Geometry/Outline")
		(27 "Margin" user)
		(31 "F.CrtYd" user "Package Geometry/Place Bound Top")
		(29 "B.CrtYd" user "Package Geometry/Place Bound Bottom")
		(35 "F.Fab" user "Ref Des/Assembly Top")
		(33 "B.Fab" user "Ref Des/Assembly Bottom")
	)
	(footprint ""
		(layer "F.Cu")
		(at 54.61 -15.621 90)
		(property "Reference" "C288"
			(at 3.556 0.54737 90)
			(unlocked yes)
			(layer "F.SilkS")
			(effects
				(font
					(size 0.7874 0.5842)
					(thickness 0.1524)
				)
			)
		)
		(property "Value" "VAL*"
			(at 0.0762 2.067306 90)
			(unlocked yes)
			(layer "F.Fab")
			(hide yes)
			(effects
				(font
					(size 0.7874 0.5842)
					(thickness 0.1524)
				)
			)
		)
		(property "Device Type" "CAPACITOR-G105-0B104-EK,0.1UF,A"
			(at 0.0508 1.127506 90)
			(unlocked yes)
			(layer "F.Fab")
			(hide yes)
			(effects
				(font
					(size 0.7874 0.5842)
					(thickness 0.1524)
				)
			)
		)
		(property "User Part Number" "PARTNUM*"
			(at 0.1016 4.023106 90)
			(unlocked yes)
			(layer "Cmts.User")
			(hide yes)
			(effects
				(font
					(size 0.7874 0.5842)
					(thickness 0.1524)
				)
			)
		)
		(property "Tolerance" "TOL*"
			(at 0.0762 3.032506 90)
			(unlocked yes)
			(layer "Cmts.User")
			(hide yes)
			(effects
				(font
					(size 0.7874 0.5842)
					(thickness 0.1524)
				)
			)
		)
		(duplicate_pad_numbers_are_jumpers no)
		(fp_line
			(start 1.143 -0.5588)
			(end -1.143 -0.5588)
			(stroke
				(width 0.1)
				(type default)
			)
			(layer "F.SilkS")
		)
		(fp_line
			(start -1.143 -0.5588)
			(end -1.143 0.5588)
			(stroke
				(width 0.1)
				(type default)
			)
			(layer "F.SilkS")
		)
		(fp_line
			(start 1.143 0.5588)
			(end 1.143 -0.5588)
			(stroke
				(width 0.1)
				(type default)
			)
			(layer "F.SilkS")
		)
		(fp_line
			(start -1.143 0.5588)
			(end 1.143 0.5588)
			(stroke
				(width 0.1)
				(type default)
			)
			(layer "F.SilkS")
		)
		(fp_poly
			(pts
				(xy -1.143 0.5588) (xy 1.143 0.5588) (xy 1.143 -0.5588) (xy -1.143 -0.5588)
			)
			(stroke
				(width 0)
				(type default)
			)
			(fill no)
			(layer "F.CrtYd")
		)
		(fp_line
			(start 0.508 -0.3048)
			(end -0.508 -0.3048)
			(stroke
				(width 0.1)
				(type default)
			)
			(layer "F.Fab")
		)
		(fp_line
			(start -0.508 -0.3048)
			(end -0.508 0.3048)
			(stroke
				(width 0.1)
				(type default)
			)
			(layer "F.Fab")
		)
		(fp_line
			(start 0.508 0.3048)
			(end 0.508 -0.3048)
			(stroke
				(width 0.1)
				(type default)
			)
			(layer "F.Fab")
		)
		(fp_line
			(start -0.508 0.3048)
			(end 0.508 0.3048)
			(stroke
				(width 0.1)
				(type default)
			)
			(layer "F.Fab")
		)
		(pad "1" smd rect
			(at -0.5334 0 90)
			(size 0.7112 0.6096)
			(layers "F.Cu" "F.Mask" "F.Paste")
			(net "XP3R3V_AUX_PCIE")
		)
		(pad "2" smd rect
			(at 0.5334 0 90)
			(size 0.7112 0.6096)
			(layers "F.Cu" "F.Mask" "F.Paste")
			(net "SG")
		)
		(zone
			(layer "F.Cu")
			(hatch none 0.5)
			(connect_pads
				(clearance 0)
			)
			(min_thickness 0.25)
			(keepout
				(tracks not_allowed)
				(vias allowed)
				(pads allowed)
				(copperpour not_allowed)
				(footprints allowed)
			)
			(placement
				(enabled no)
				(sheetname "")
			)
			(fill
				(thermal_gap 0.5)
				(thermal_bridge_width 0.5)
				(island_removal_mode 0)
			)
			(polygon
				(pts
					(xy 54.9148 -15.5448) (xy 54.9148 -15.6972) (xy 54.3052 -15.6972) (xy 54.3052 -15.5448)
				)
			)
		)
		(zone
			(layer "F.Cu")
			(hatch none 0.5)
			(connect_pads
				(clearance 0)
			)
			(min_thickness 0.25)
			(keepout
				(tracks allowed)
				(vias not_allowed)
				(pads allowed)
				(copperpour not_allowed)
				(footprints allowed)
			)
			(placement
				(enabled no)
				(sheetname "")
			)
			(fill
				(thermal_gap 0.5)
				(thermal_bridge_width 0.5)
				(island_removal_mode 0)
			)
			(polygon
				(pts
					(xy 54.9148 -15.5448) (xy 54.9148 -15.6972) (xy 54.3052 -15.6972) (xy 54.3052 -15.5448)
				)
			)
		)
	)
	(footprint ""
		(layer "F.Cu")
		(at 115.062 -98.298 90)
		(property "Reference" "C81"
			(at 0.127 -1.35763 90)
			(unlocked yes)
			(layer "F.SilkS")
			(effects
				(font
					(size 0.7874 0.5842)
					(thickness 0.1524)
				)
			)
		)
		(property "Value" "VAL*"
			(at 0.0762 2.067306 90)
			(unlocked yes)
			(layer "F.Fab")
			(hide yes)
			(effects
				(font
					(size 0.7874 0.5842)
					(thickness 0.1524)
				)
			)
		)
		(property "Tolerance" "TOL*"
			(at 0.0762 3.032506 90)
			(unlocked yes)
			(layer "Cmts.User")
			(hide yes)
			(effects
				(font
					(size 0.7874 0.5842)
					(thickness 0.1524)
				)
			)
		)
		(property "User Part Number" "PARTNUM*"
			(at 0.1016 4.023106 90)
			(unlocked yes)
			(layer "Cmts.User")
			(hide yes)
			(effects
				(font
					(size 0.7874 0.5842)
					(thickness 0.1524)
				)
			)
		)
		(property "Device Type" "CAPACITOR-G105-0B104-CK,0.1UF,A"
			(at 0.0508 1.127506 90)
			(unlocked yes)
			(layer "F.Fab")
			(hide yes)
			(effects
				(font
					(size 0.7874 0.5842)
					(thickness 0.1524)
				)
			)
		)
		(duplicate_pad_numbers_are_jumpers no)
		(fp_line
			(start 1.143 -0.5588)
			(end -1.143 -0.5588)
			(stroke
				(width 0.1)
				(type default)
			)
			(layer "F.SilkS")
		)
		(fp_line
			(start -1.143 -0.5588)
			(end -1.143 0.5588)
			(stroke
				(width 0.1)
				(type default)
			)
			(layer "F.SilkS")
		)
		(fp_line
			(start 1.143 0.5588)
			(end 1.143 -0.5588)
			(stroke
				(width 0.1)
				(type default)
			)
			(layer "F.SilkS")
		)
		(fp_line
			(start -1.143 0.5588)
			(end 1.143 0.5588)
			(stroke
				(width 0.1)
				(type default)
			)
			(layer "F.SilkS")
		)
		(fp_rect
			(start -1.143 0.5588)
			(end 1.143 -0.5588)
			(stroke
				(width 0)
				(type default)
			)
			(fill no)
			(layer "F.CrtYd")
		)
		(fp_line
			(start 0.508 -0.3048)
			(end -0.508 -0.3048)
			(stroke
				(width 0.1)
				(type default)
			)
			(layer "F.Fab")
		)
		(fp_line
			(start -0.508 -0.3048)
			(end -0.508 0.3048)
			(stroke
				(width 0.1)
				(type default)
			)
			(layer "F.Fab")
		)
		(fp_line
			(start 0.508 0.3048)
			(end 0.508 -0.3048)
			(stroke
				(width 0.1)
				(type default)
			)
			(layer "F.Fab")
		)
		(fp_line
			(start -0.508 0.3048)
			(end 0.508 0.3048)
			(stroke
				(width 0.1)
				(type default)
			)
			(layer "F.Fab")
		)
		(pad "1" smd rect
			(at -0.5334 0 90)
			(size 0.7112 0.6096)
			(layers "F.Cu" "F.Mask" "F.Paste")
			(net "XP3R3V_FPGA")
		)
		(pad "2" smd rect
			(at 0.5334 0 90)
			(size 0.7112 0.6096)
			(layers "F.Cu" "F.Mask" "F.Paste")
			(net "SG")
		)
		(zone
			(layer "F.Cu")
			(hatch none 0.5)
			(connect_pads
				(clearance 0)
			)
			(min_thickness 0.25)
			(keepout
				(tracks allowed)
				(vias not_allowed)
				(pads allowed)
				(copperpour not_allowed)
				(footprints allowed)
			)
			(placement
				(enabled no)
				(sheetname "")
			)
			(fill
				(thermal_gap 0.5)
				(thermal_bridge_width 0.5)
				(island_removal_mode 0)
			)
			(polygon
				(pts
					(xy 115.3668 -98.2218) (xy 115.3668 -98.3742) (xy 114.7572 -98.3742) (xy 114.7572 -98.2218)
				)
			)
		)
	)
)
